FILE_TYPE = MACRO_DRAWING;
SET COLOR_WIRE YELLOW;
SET COLOR_PROP ORANGE;
SET COLOR_DOT WHITE;
SET COLOR_ARC YELLOW;
SET COLOR_BODY GREEN;
SET COLOR_NOTE PURPLE;
SET PROP_DISPLAY VALUE;
SET PAGE_NUMBER P241;
FORCEADD UNIVERSAL_GND..1
(-13450 1450);
FORCEPROP 3 LASTPIN (-13450 1500) SIG_NAME GND\g
J 0
(-13440 1510);
DISPLAY 0.659574 (-13440 1510);
PAINT MONO (-13440 1510);
DISPLAY INVISIBLE (-13440 1510);
FORCEPROP 1 LAST PATH I10
J 0
(-13375 1450);
DISPLAY 0.872340 (-13375 1450);
PAINT AQUA (-13375 1450);
DISPLAY INVISIBLE (-13375 1450);
FORCEPROP 2 LAST CDS_LIB logical_power
J 0
(-13450 1450);
DISPLAY INVISIBLE (-13450 1450);
FORCEPROP 1 LAST HDL_POWER GND
J 1
(-13425 1375);
DISPLAY 0.872340 (-13425 1375);
PAINT GREEN (-13425 1375);
DISPLAY INVISIBLE (-13425 1375);
FORCEADD Q_LED..1
R 2
(-12375 700);
FORCEPROP 1 LAST PART_NUMBER BEBL0172Z00
J 0
(-12475 475);
DISPLAY 0.574468 (-12475 475);
PAINT GREEN (-12475 475);
DISPLAY INVISIBLE (-12475 475);
FORCEPROP 1 LAST MATERIAL IC
J 0
(-12350 525);
DISPLAY 0.723404 (-12350 525);
PAINT GREEN (-12350 525);
FORCEPROP 2 LAST MANUF_PN LTST-C281TBKT-5A
J 0
(-12475 425);
DISPLAY 0.638298 (-12475 425);
FORCEPROP 0 LAST PACK_TYPE SMLF
J 0
(-12475 525);
DISPLAY 0.638298 (-12475 525);
FORCEPROP 1 LAST LOCATION D89
J 0
(-12475 625);
DISPLAY 0.723404 (-12475 625);
PAINT GREEN (-12475 625);
FORCEPROP 0 LASTPIN (-12225 700) $PN A
J 0
(-12215 710);
DISPLAY 0.808511 (-12215 710);
FORCEPROP 0 LASTPIN (-12525 700) $PN C
J 2
(-12535 710);
DISPLAY 0.808511 (-12535 710);
FORCEPROP 2 LAST COLOR LED_BLUE
J 0
(-12475 575);
DISPLAY 0.638298 (-12475 575);
FORCEPROP 1 LAST PATH I11
J 2
(-12500 780);
DISPLAY 0.723404 (-12500 780);
PAINT GREEN (-12500 780);
DISPLAY INVISIBLE (-12500 780);
FORCEPROP 2 LAST CDS_LIB pure_quanta
J 0
(-12375 700);
DISPLAY INVISIBLE (-12375 700);
FORCEPROP 1 LAST NEEDS_NO_SIZE TRUE
J 2
(-12353 722);
DISPLAY 0.468085 (-12353 722);
PAINT GREEN (-12353 722);
DISPLAY INVISIBLE (-12353 722);
FORCEPROP 0 LAST $SEC 1
J 0
(-12475 675);
DISPLAY INVISIBLE (-12475 675);
FORCEPROP 0 LAST CDS_SEC 1
J 0
(-12475 675);
DISPLAY INVISIBLE (-12475 675);
FORCEADD UNIVERSAL_POWER..1
(-10450 875);
FORCEPROP 3 LASTPIN (-10450 825) SIG_NAME P3V3_AUX\g
J 0
(-10440 835);
DISPLAY 0.659574 (-10440 835);
PAINT MONO (-10440 835);
DISPLAY INVISIBLE (-10440 835);
FORCEPROP 1 LAST HDL_POWER P3V3_AUX
J 1
(-10450 925);
DISPLAY 0.723404 (-10450 925);
PAINT GREEN (-10450 925);
FORCEPROP 2 LAST CDS_LIB logical_power
J 0
(-10450 875);
DISPLAY INVISIBLE (-10450 875);
FORCEPROP 1 LAST PATH I15
J 0
(-10400 900);
DISPLAY 0.872340 (-10400 900);
PAINT AQUA (-10400 900);
DISPLAY INVISIBLE (-10400 900);
FORCEADD MOSFET_NCH_DUAL..2
(-13500 1800);
FORCEPROP 1 LAST PART_NUMBER BAM138K0003
J 0
(-13349 1706);
DISPLAY 0.723404 (-13349 1706);
PAINT BLUE (-13349 1706);
DISPLAY INVISIBLE (-13349 1706);
FORCEPROP 2 LAST VALUE PJT138K
J 0
(-13325 1825);
DISPLAY 0.723404 (-13325 1825);
PAINT SKYBLUE (-13325 1825);
FORCEPROP 2 LAST PART_TYPE SMLF
J 0
(-13325 1875);
DISPLAY 1.021277 (-13325 1875);
FORCEPROP 1 LAST MATERIAL IC
J 0
(-13349 1651);
DISPLAY 0.723404 (-13349 1651);
PAINT SKYBLUE (-13349 1651);
FORCEPROP 1 LAST LOCATION Q87
J 0
(-13349 1776);
DISPLAY 0.723404 (-13349 1776);
PAINT AQUA (-13349 1776);
FORCEPROP 2 LASTPIN (-13450 2000) $PN 3
R 1
J 0
(-13460 2010);
DISPLAY 0.723404 (-13460 2010);
PAINT MONO (-13460 2010);
FORCEPROP 2 LASTPIN (-13700 1750) $PN 5
J 2
(-13710 1760);
DISPLAY 0.723404 (-13710 1760);
PAINT MONO (-13710 1760);
FORCEPROP 2 LASTPIN (-13450 1600) $PN 4
R 1
J 2
(-13460 1590);
DISPLAY 0.723404 (-13460 1590);
PAINT MONO (-13460 1590);
FORCEPROP 1 LAST CDS_LMAN_SYM_OUTLINE -150,150,150,-150
J 0
(-13500 1800);
DISPLAY 0.468085 (-13500 1800);
PAINT GREEN (-13500 1800);
DISPLAY INVISIBLE (-13500 1800);
FORCEPROP 2 LAST CDS_LIB pure_quanta
J 0
(-13500 1800);
DISPLAY INVISIBLE (-13500 1800);
FORCEPROP 2 LAST SEC_TYPE 
J 0
(-13325 1925);
DISPLAY 1.021277 (-13325 1925);
DISPLAY INVISIBLE (-13325 1925);
FORCEPROP 1 LAST PATH I16
J 0
(-13350 1650);
DISPLAY 0.723404 (-13350 1650);
PAINT GREEN (-13350 1650);
DISPLAY INVISIBLE (-13350 1650);
FORCEPROP 1 LAST NEEDS_NO_SIZE TRUE
J 0
(-13350 1691);
DISPLAY 0.468085 (-13350 1691);
PAINT GREEN (-13350 1691);
DISPLAY INVISIBLE (-13350 1691);
FORCEPROP 2 LAST SEC 2
J 0
(-13325 1925);
DISPLAY 0.680851 (-13325 1925);
PAINT MONO (-13325 1925);
DISPLAY INVISIBLE (-13325 1925);
FORCEADD MOSFET_NCH_DUAL..1
(-13500 3075);
FORCEPROP 1 LAST PART_NUMBER BAM138K0003
J 0
(-13349 2989);
DISPLAY 0.723404 (-13349 2989);
PAINT GREEN (-13349 2989);
DISPLAY INVISIBLE (-13349 2989);
FORCEPROP 2 LAST PART_TYPE SMLF
J 0
(-13325 3150);
DISPLAY 1.021277 (-13325 3150);
FORCEPROP 2 LAST VALUE PJT138K
J 0
(-13325 3100);
DISPLAY 1.021277 (-13325 3100);
FORCEPROP 1 LAST MATERIAL IC
J 0
(-13349 2924);
DISPLAY 0.723404 (-13349 2924);
PAINT GREEN (-13349 2924);
FORCEPROP 1 LAST LOCATION Q87
J 0
(-13349 3049);
DISPLAY 0.723404 (-13349 3049);
PAINT GREEN (-13349 3049);
FORCEPROP 0 LASTPIN (-13450 3275) $PN 6
R 1
J 0
(-13460 3285);
DISPLAY 0.808511 (-13460 3285);
FORCEPROP 0 LASTPIN (-13700 3025) $PN 2
J 2
(-13710 3035);
DISPLAY 0.808511 (-13710 3035);
FORCEPROP 0 LASTPIN (-13450 2875) $PN 1
R 1
J 2
(-13460 2865);
DISPLAY 0.808511 (-13460 2865);
FORCEPROP 1 LAST PATH I17
J 0
(-13500 3075);
DISPLAY 0.723404 (-13500 3075);
PAINT GREEN (-13500 3075);
DISPLAY INVISIBLE (-13500 3075);
FORCEPROP 1 LAST CDS_LMAN_SYM_OUTLINE -150,150,150,-150
J 0
(-13500 3075);
DISPLAY 0.468085 (-13500 3075);
PAINT GREEN (-13500 3075);
DISPLAY INVISIBLE (-13500 3075);
FORCEPROP 2 LAST CDS_LIB pure_quanta
J 0
(-13500 3075);
DISPLAY INVISIBLE (-13500 3075);
FORCEPROP 1 LAST NEEDS_NO_SIZE TRUE
J 0
(-13500 3074);
DISPLAY 0.468085 (-13500 3074);
PAINT GREEN (-13500 3074);
DISPLAY INVISIBLE (-13500 3074);
FORCEPROP 0 LAST $SEC 1
J 0
(-13325 3200);
DISPLAY INVISIBLE (-13325 3200);
FORCEPROP 0 LAST CDS_SEC 1
J 0
(-13325 3200);
DISPLAY INVISIBLE (-13325 3200);
FORCEADD UNIVERSAL_GND..1
(-13450 2725);
FORCEPROP 3 LASTPIN (-13450 2775) SIG_NAME GND\g
J 0
(-13440 2785);
DISPLAY 0.659574 (-13440 2785);
PAINT MONO (-13440 2785);
DISPLAY INVISIBLE (-13440 2785);
FORCEPROP 1 LAST PATH I18
J 0
(-13375 2725);
DISPLAY 0.872340 (-13375 2725);
PAINT AQUA (-13375 2725);
DISPLAY INVISIBLE (-13375 2725);
FORCEPROP 2 LAST CDS_LIB logical_power
J 0
(-13450 2725);
DISPLAY INVISIBLE (-13450 2725);
FORCEPROP 1 LAST HDL_POWER GND
J 1
(-13425 2650);
DISPLAY 0.872340 (-13425 2650);
PAINT GREEN (-13425 2650);
DISPLAY INVISIBLE (-13425 2650);
FORCEADD Q_LED..1
R 2
(-12425 2075);
FORCEPROP 1 LAST PART_NUMBER BEBL0172Z00
J 0
(-12525 1850);
DISPLAY 0.574468 (-12525 1850);
PAINT GREEN (-12525 1850);
DISPLAY INVISIBLE (-12525 1850);
FORCEPROP 2 LAST MANUF_PN LTST-C281TBKT-5A
J 0
(-12525 1800);
DISPLAY 0.638298 (-12525 1800);
FORCEPROP 2 LAST COLOR LED_BLUE
J 0
(-12525 1950);
DISPLAY 0.638298 (-12525 1950);
FORCEPROP 0 LAST PACK_TYPE SMLF
J 0
(-12525 1900);
DISPLAY 0.638298 (-12525 1900);
FORCEPROP 1 LAST MATERIAL IC
J 0
(-12400 1900);
DISPLAY 0.723404 (-12400 1900);
PAINT GREEN (-12400 1900);
FORCEPROP 1 LAST LOCATION D88
J 0
(-12525 1975);
DISPLAY 0.723404 (-12525 1975);
PAINT GREEN (-12525 1975);
FORCEPROP 0 LASTPIN (-12275 2075) $PN A
J 0
(-12265 2085);
DISPLAY 0.808511 (-12265 2085);
FORCEPROP 0 LASTPIN (-12575 2075) $PN C
J 2
(-12585 2085);
DISPLAY 0.808511 (-12585 2085);
FORCEPROP 1 LAST PATH I19
J 2
(-12550 2155);
DISPLAY 0.723404 (-12550 2155);
PAINT GREEN (-12550 2155);
DISPLAY INVISIBLE (-12550 2155);
FORCEPROP 2 LAST CDS_LIB pure_quanta
J 0
(-12425 2075);
DISPLAY INVISIBLE (-12425 2075);
FORCEPROP 1 LAST NEEDS_NO_SIZE TRUE
J 2
(-12403 2097);
DISPLAY 0.468085 (-12403 2097);
PAINT GREEN (-12403 2097);
DISPLAY INVISIBLE (-12403 2097);
FORCEPROP 0 LAST $SEC 1
J 0
(-12525 2050);
DISPLAY INVISIBLE (-12525 2050);
FORCEPROP 0 LAST CDS_SEC 1
J 0
(-12525 2050);
DISPLAY INVISIBLE (-12525 2050);
FORCEADD Q_LED..1
R 2
(-12425 3350);
FORCEPROP 1 LAST PART_NUMBER BEBL0172Z00
J 0
(-12525 3125);
DISPLAY 0.574468 (-12525 3125);
PAINT GREEN (-12525 3125);
DISPLAY INVISIBLE (-12525 3125);
FORCEPROP 2 LAST MANUF_PN LTST-C281TBKT-5A
J 0
(-12525 3075);
DISPLAY 0.638298 (-12525 3075);
FORCEPROP 2 LAST COLOR LED_BLUE
J 0
(-12525 3225);
DISPLAY 0.638298 (-12525 3225);
FORCEPROP 1 LAST MATERIAL IC
J 0
(-12400 3175);
DISPLAY 0.723404 (-12400 3175);
PAINT GREEN (-12400 3175);
FORCEPROP 0 LAST PACK_TYPE SMLF
J 0
(-12525 3175);
DISPLAY 0.638298 (-12525 3175);
FORCEPROP 1 LAST LOCATION D87
J 0
(-12525 3275);
DISPLAY 0.723404 (-12525 3275);
PAINT GREEN (-12525 3275);
FORCEPROP 0 LASTPIN (-12275 3350) $PN A
J 0
(-12265 3360);
DISPLAY 0.808511 (-12265 3360);
FORCEPROP 0 LASTPIN (-12575 3350) $PN C
J 2
(-12585 3360);
DISPLAY 0.808511 (-12585 3360);
FORCEPROP 1 LAST PATH I20
J 2
(-12550 3430);
DISPLAY 0.723404 (-12550 3430);
PAINT GREEN (-12550 3430);
DISPLAY INVISIBLE (-12550 3430);
FORCEPROP 1 LAST NEEDS_NO_SIZE TRUE
J 2
(-12403 3372);
DISPLAY 0.468085 (-12403 3372);
PAINT GREEN (-12403 3372);
DISPLAY INVISIBLE (-12403 3372);
FORCEPROP 2 LAST CDS_LIB pure_quanta
R 3
J 0
(-12378 3397);
DISPLAY INVISIBLE (-12378 3397);
FORCEPROP 0 LAST $SEC 1
J 0
(-12525 3325);
DISPLAY INVISIBLE (-12525 3325);
FORCEPROP 0 LAST CDS_SEC 1
J 0
(-12525 3325);
DISPLAY INVISIBLE (-12525 3325);
FORCEADD UNIVERSAL_POWER..1
(-10475 2275);
FORCEPROP 3 LASTPIN (-10475 2225) SIG_NAME P3V3_AUX\g
J 0
(-10465 2235);
DISPLAY 0.659574 (-10465 2235);
PAINT MONO (-10465 2235);
DISPLAY INVISIBLE (-10465 2235);
FORCEPROP 1 LAST HDL_POWER P3V3_AUX
J 1
(-10475 2325);
DISPLAY 0.723404 (-10475 2325);
PAINT GREEN (-10475 2325);
FORCEPROP 1 LAST PATH I24
J 0
(-10425 2300);
DISPLAY 0.872340 (-10425 2300);
PAINT AQUA (-10425 2300);
DISPLAY INVISIBLE (-10425 2300);
FORCEPROP 2 LAST CDS_LIB logical_power
J 0
(-10475 2275);
DISPLAY INVISIBLE (-10475 2275);
FORCEADD UNIVERSAL_POWER..1
(-10425 3650);
FORCEPROP 3 LASTPIN (-10425 3600) SIG_NAME P3V3_AUX\g
J 0
(-10415 3610);
DISPLAY 0.659574 (-10415 3610);
PAINT MONO (-10415 3610);
DISPLAY INVISIBLE (-10415 3610);
FORCEPROP 1 LAST HDL_POWER P3V3_AUX
J 1
(-10425 3700);
DISPLAY 0.723404 (-10425 3700);
PAINT GREEN (-10425 3700);
FORCEPROP 1 LAST PATH I25
J 0
(-10375 3675);
DISPLAY 0.872340 (-10375 3675);
PAINT AQUA (-10375 3675);
DISPLAY INVISIBLE (-10375 3675);
FORCEPROP 2 LAST CDS_LIB logical_power
J 0
(-10425 3650);
DISPLAY INVISIBLE (-10425 3650);
FORCEADD OFFPAGE..1
(-14525 -1075);
PAINT AQUA (-14525 -1075);
FORCEPROP 2 LAST $XR1 223 
J 0
(-14897 -1075);
DISPLAY 0.638298 (-14897 -1075);
PAINT MONO (-14897 -1075);
FORCEPROP 2 LAST $XR0 183 
J 0
(-14777 -1075);
DISPLAY 0.638298 (-14777 -1075);
PAINT MONO (-14777 -1075);
FORCEPROP 2 LAST PATH I26
J 0
(-14800 -1025);
DISPLAY 1.021277 (-14800 -1025);
DISPLAY INVISIBLE (-14800 -1025);
FORCEPROP 2 LAST CDS_LIB standard
J 0
(-14525 -1075);
DISPLAY INVISIBLE (-14525 -1075);
FORCEPROP 1 LAST OFFPAGE TRUE
J 0
(-14200 -1200);
DISPLAY 0.872340 (-14200 -1200);
PAINT AQUA (-14200 -1200);
DISPLAY INVISIBLE (-14200 -1200);
FORCEPROP 1 LAST COMMENT_BODY TRUE
J 0
(-14400 -1175);
DISPLAY 0.872340 (-14400 -1175);
PAINT GREEN (-14400 -1175);
DISPLAY INVISIBLE (-14400 -1175);
FORCEADD OFFPAGE..1
(-14550 375);
PAINT AQUA (-14550 375);
FORCEPROP 2 LAST $XR1 216 
J 0
(-14922 375);
DISPLAY 0.638298 (-14922 375);
PAINT MONO (-14922 375);
FORCEPROP 2 LAST $XR0 226 
J 0
(-14802 375);
DISPLAY 0.638298 (-14802 375);
PAINT MONO (-14802 375);
FORCEPROP 2 LAST CDS_LIB standard
J 0
(-14550 375);
DISPLAY INVISIBLE (-14550 375);
FORCEPROP 2 LAST PATH I3
J 0
(-14825 450);
DISPLAY 1.021277 (-14825 450);
DISPLAY INVISIBLE (-14825 450);
FORCEPROP 1 LAST COMMENT_BODY TRUE
J 0
(-14425 275);
DISPLAY 0.872340 (-14425 275);
PAINT GREEN (-14425 275);
DISPLAY INVISIBLE (-14425 275);
FORCEPROP 1 LAST OFFPAGE TRUE
J 0
(-14225 250);
DISPLAY 0.872340 (-14225 250);
PAINT AQUA (-14225 250);
DISPLAY INVISIBLE (-14225 250);
FORCEADD UNIVERSAL_GND..1
(-13375 -1375);
FORCEPROP 3 LASTPIN (-13375 -1325) SIG_NAME GND\g
J 0
(-13365 -1315);
DISPLAY 0.659574 (-13365 -1315);
PAINT MONO (-13365 -1315);
DISPLAY INVISIBLE (-13365 -1315);
FORCEPROP 1 LAST HDL_POWER GND
J 1
(-13350 -1450);
DISPLAY 0.872340 (-13350 -1450);
PAINT GREEN (-13350 -1450);
DISPLAY INVISIBLE (-13350 -1450);
FORCEPROP 2 LAST CDS_LIB logical_power
J 0
(-13375 -1375);
DISPLAY INVISIBLE (-13375 -1375);
FORCEPROP 1 LAST PATH I31
J 0
(-13300 -1375);
DISPLAY 0.872340 (-13300 -1375);
PAINT AQUA (-13300 -1375);
DISPLAY INVISIBLE (-13300 -1375);
FORCEADD Q_LED..1
R 2
(-12350 -750);
FORCEPROP 1 LAST PART_NUMBER BEBL0172Z00
J 0
(-12450 -975);
DISPLAY 0.574468 (-12450 -975);
PAINT GREEN (-12450 -975);
DISPLAY INVISIBLE (-12450 -975);
FORCEPROP 1 LAST MATERIAL IC
J 0
(-12325 -925);
DISPLAY 0.723404 (-12325 -925);
PAINT GREEN (-12325 -925);
FORCEPROP 0 LAST PACK_TYPE SMLF
J 0
(-12450 -925);
DISPLAY 0.638298 (-12450 -925);
FORCEPROP 2 LAST MANUF_PN LTST-C281TBKT-5A
J 0
(-12450 -1025);
DISPLAY 0.638298 (-12450 -1025);
FORCEPROP 2 LAST COLOR LED_BLUE
J 0
(-12450 -875);
DISPLAY 0.638298 (-12450 -875);
FORCEPROP 1 LAST LOCATION D90
J 0
(-12450 -825);
DISPLAY 0.723404 (-12450 -825);
PAINT GREEN (-12450 -825);
FORCEPROP 0 LASTPIN (-12200 -750) $PN A
J 0
(-12190 -740);
DISPLAY 0.808511 (-12190 -740);
FORCEPROP 0 LASTPIN (-12500 -750) $PN C
J 2
(-12510 -740);
DISPLAY 0.808511 (-12510 -740);
FORCEPROP 1 LAST PATH I33
J 2
(-12475 -670);
DISPLAY 0.723404 (-12475 -670);
PAINT GREEN (-12475 -670);
DISPLAY INVISIBLE (-12475 -670);
FORCEPROP 2 LAST CDS_LIB pure_quanta
J 0
(-12350 -750);
DISPLAY INVISIBLE (-12350 -750);
FORCEPROP 1 LAST NEEDS_NO_SIZE TRUE
J 2
(-12328 -728);
DISPLAY 0.468085 (-12328 -728);
PAINT GREEN (-12328 -728);
DISPLAY INVISIBLE (-12328 -728);
FORCEPROP 0 LAST $SEC 1
J 0
(-12450 -775);
DISPLAY INVISIBLE (-12450 -775);
FORCEPROP 0 LAST CDS_SEC 1
J 0
(-12450 -775);
DISPLAY INVISIBLE (-12450 -775);
FORCEADD UNIVERSAL_POWER..1
(-10325 -575);
FORCEPROP 3 LASTPIN (-10325 -625) SIG_NAME P3V3_AUX\g
J 0
(-10315 -615);
DISPLAY 0.659574 (-10315 -615);
PAINT MONO (-10315 -615);
DISPLAY INVISIBLE (-10315 -615);
FORCEPROP 1 LAST HDL_POWER P3V3_AUX
J 1
(-10325 -525);
DISPLAY 0.723404 (-10325 -525);
PAINT GREEN (-10325 -525);
FORCEPROP 1 LAST PATH I37
J 0
(-10275 -550);
DISPLAY 0.872340 (-10275 -550);
PAINT AQUA (-10275 -550);
DISPLAY INVISIBLE (-10275 -550);
FORCEPROP 2 LAST CDS_LIB logical_power
J 0
(-10325 -575);
DISPLAY INVISIBLE (-10325 -575);
FORCEADD Q_RES..1
(-11125 3350);
FORCEPROP 1 LAST PART_NUMBER CS11302FB03
J 0
(-11350 3450);
DISPLAY 0.638298 (-11350 3450);
DISPLAY INVISIBLE (-11350 3450);
FORCEPROP 1 LAST PACK_TYPE 0402LF
J 0
(-10825 3350);
DISPLAY 0.638298 (-10825 3350);
FORCEPROP 1 LAST TOLERANCE 1%
J 0
(-10900 3350);
DISPLAY 0.638298 (-10900 3350);
FORCEPROP 1 LAST VALUE 130
J 2
(-10925 3350);
DISPLAY 0.638298 (-10925 3350);
FORCEPROP 1 LAST WATTAGE 1/16W
J 2
(-10975 3300);
DISPLAY 0.638298 (-10975 3300);
FORCEPROP 1 LAST MATERIAL CHIP
J 0
(-11275 3300);
DISPLAY 0.638298 (-11275 3300);
FORCEPROP 1 LAST $LOCATION R3068
J 0
(-11175 3400);
DISPLAY 0.978723 (-11175 3400);
FORCEPROP 1 LASTPIN (-11225 3350) $PN 1
J 0
(-11213 3362);
DISPLAY 0.787234 (-11213 3362);
PAINT MONO (-11213 3362);
FORCEPROP 1 LASTPIN (-11025 3350) $PN 2
J 0
(-11063 3362);
DISPLAY 0.787234 (-11063 3362);
PAINT MONO (-11063 3362);
FORCEPROP 2 LAST CDS_LIB pure_quanta
J 0
(-11125 3350);
DISPLAY INVISIBLE (-11125 3350);
FORCEPROP 1 LAST PATH I38
J 0
(-11175 3500);
DISPLAY 0.978723 (-11175 3500);
PAINT WHITE (-11175 3500);
DISPLAY INVISIBLE (-11175 3500);
FORCEPROP 0 LAST CDS_LOCATION R3068
J 0
(-11175 3450);
DISPLAY 1.021277 (-11175 3450);
DISPLAY INVISIBLE (-11175 3450);
FORCEPROP 0 LAST $SEC 1
J 0
(-11175 3450);
DISPLAY 0.680851 (-11175 3450);
PAINT MONO (-11175 3450);
DISPLAY INVISIBLE (-11175 3450);
FORCEPROP 0 LAST CDS_SEC 1
J 0
(-11175 3450);
DISPLAY 1.021277 (-11175 3450);
DISPLAY INVISIBLE (-11175 3450);
FORCEADD Q_RES..1
(-11125 2075);
FORCEPROP 1 LAST PART_NUMBER CS11302FB03
J 0
(-11350 2175);
DISPLAY 0.638298 (-11350 2175);
DISPLAY INVISIBLE (-11350 2175);
FORCEPROP 1 LAST MATERIAL CHIP
J 0
(-11275 2025);
DISPLAY 0.638298 (-11275 2025);
FORCEPROP 1 LAST WATTAGE 1/16W
J 2
(-10975 2025);
DISPLAY 0.638298 (-10975 2025);
FORCEPROP 1 LAST TOLERANCE 1%
J 0
(-10900 2075);
DISPLAY 0.638298 (-10900 2075);
FORCEPROP 1 LAST VALUE 130
J 2
(-10925 2075);
DISPLAY 0.638298 (-10925 2075);
FORCEPROP 1 LAST PACK_TYPE 0402LF
J 0
(-10825 2075);
DISPLAY 0.638298 (-10825 2075);
FORCEPROP 1 LAST $LOCATION R3069
J 0
(-11175 2125);
DISPLAY 0.978723 (-11175 2125);
FORCEPROP 1 LASTPIN (-11225 2075) $PN 1
J 0
(-11213 2087);
DISPLAY 0.787234 (-11213 2087);
PAINT MONO (-11213 2087);
FORCEPROP 1 LASTPIN (-11025 2075) $PN 2
J 0
(-11063 2087);
DISPLAY 0.787234 (-11063 2087);
PAINT MONO (-11063 2087);
FORCEPROP 2 LAST CDS_LIB pure_quanta
J 0
(-11125 2075);
DISPLAY INVISIBLE (-11125 2075);
FORCEPROP 1 LAST PATH I39
J 0
(-11175 2225);
DISPLAY 0.978723 (-11175 2225);
PAINT WHITE (-11175 2225);
DISPLAY INVISIBLE (-11175 2225);
FORCEPROP 0 LAST CDS_LOCATION R3069
J 0
(-11175 2175);
DISPLAY 1.021277 (-11175 2175);
DISPLAY INVISIBLE (-11175 2175);
FORCEPROP 0 LAST $SEC 1
J 0
(-11175 2175);
DISPLAY 0.680851 (-11175 2175);
PAINT MONO (-11175 2175);
DISPLAY INVISIBLE (-11175 2175);
FORCEPROP 0 LAST CDS_SEC 1
J 0
(-11175 2175);
DISPLAY 1.021277 (-11175 2175);
DISPLAY INVISIBLE (-11175 2175);
FORCEADD OFFPAGE..1
(-14600 1750);
PAINT AQUA (-14600 1750);
FORCEPROP 2 LAST $XR2 222 
J 0
(-15122 1750);
DISPLAY 0.638298 (-15122 1750);
PAINT MONO (-15122 1750);
FORCEPROP 2 LAST $XR1 220 
J 0
(-15002 1750);
DISPLAY 0.638298 (-15002 1750);
PAINT MONO (-15002 1750);
FORCEPROP 2 LAST $XR0 214 
J 0
(-14882 1750);
DISPLAY 0.638298 (-14882 1750);
PAINT MONO (-14882 1750);
FORCEPROP 2 LAST PATH I4
J 0
(-14850 1800);
DISPLAY 1.021277 (-14850 1800);
DISPLAY INVISIBLE (-14850 1800);
FORCEPROP 2 LAST CDS_LIB standard
J 0
(-14600 1750);
DISPLAY INVISIBLE (-14600 1750);
FORCEPROP 1 LAST OFFPAGE TRUE
J 0
(-14275 1625);
DISPLAY 0.872340 (-14275 1625);
PAINT AQUA (-14275 1625);
DISPLAY INVISIBLE (-14275 1625);
FORCEPROP 1 LAST COMMENT_BODY TRUE
J 0
(-14475 1650);
DISPLAY 0.872340 (-14475 1650);
PAINT GREEN (-14475 1650);
DISPLAY INVISIBLE (-14475 1650);
FORCEADD Q_RES..1
(-11075 700);
FORCEPROP 1 LAST PART_NUMBER CS11302FB03
J 0
(-11300 800);
DISPLAY 0.638298 (-11300 800);
DISPLAY INVISIBLE (-11300 800);
FORCEPROP 1 LAST VALUE 130
J 2
(-10875 700);
DISPLAY 0.638298 (-10875 700);
FORCEPROP 1 LAST MATERIAL CHIP
J 0
(-11225 650);
DISPLAY 0.638298 (-11225 650);
FORCEPROP 1 LAST PACK_TYPE 0402LF
J 0
(-10775 700);
DISPLAY 0.638298 (-10775 700);
FORCEPROP 1 LAST WATTAGE 1/16W
J 2
(-10925 650);
DISPLAY 0.638298 (-10925 650);
FORCEPROP 1 LAST TOLERANCE 1%
J 0
(-10850 700);
DISPLAY 0.638298 (-10850 700);
FORCEPROP 1 LAST $LOCATION R1044
J 0
(-11125 750);
DISPLAY 0.978723 (-11125 750);
FORCEPROP 1 LASTPIN (-11175 700) $PN 1
J 0
(-11163 712);
DISPLAY 0.787234 (-11163 712);
PAINT MONO (-11163 712);
FORCEPROP 1 LASTPIN (-10975 700) $PN 2
J 0
(-11013 712);
DISPLAY 0.787234 (-11013 712);
PAINT MONO (-11013 712);
FORCEPROP 2 LAST CDS_LIB pure_quanta
J 0
(-11075 700);
DISPLAY INVISIBLE (-11075 700);
FORCEPROP 1 LAST PATH I40
J 0
(-11125 850);
DISPLAY 0.978723 (-11125 850);
PAINT WHITE (-11125 850);
DISPLAY INVISIBLE (-11125 850);
FORCEPROP 0 LAST CDS_LOCATION R1044
J 0
(-11125 800);
DISPLAY 1.021277 (-11125 800);
DISPLAY INVISIBLE (-11125 800);
FORCEPROP 0 LAST $SEC 1
J 0
(-11125 800);
DISPLAY 0.680851 (-11125 800);
PAINT MONO (-11125 800);
DISPLAY INVISIBLE (-11125 800);
FORCEPROP 0 LAST CDS_SEC 1
J 0
(-11125 800);
DISPLAY 1.021277 (-11125 800);
DISPLAY INVISIBLE (-11125 800);
FORCEADD Q_RES..1
(-10950 -750);
FORCEPROP 1 LAST PART_NUMBER CS11302FB03
J 0
(-11175 -650);
DISPLAY 0.638298 (-11175 -650);
DISPLAY INVISIBLE (-11175 -650);
FORCEPROP 1 LAST VALUE 130
J 2
(-10750 -750);
DISPLAY 0.638298 (-10750 -750);
FORCEPROP 1 LAST TOLERANCE 1%
J 0
(-10725 -750);
DISPLAY 0.638298 (-10725 -750);
FORCEPROP 1 LAST MATERIAL CHIP
J 0
(-11100 -800);
DISPLAY 0.638298 (-11100 -800);
FORCEPROP 1 LAST WATTAGE 1/16W
J 2
(-10800 -800);
DISPLAY 0.638298 (-10800 -800);
FORCEPROP 1 LAST PACK_TYPE 0402LF
J 0
(-10650 -750);
DISPLAY 0.638298 (-10650 -750);
FORCEPROP 1 LAST $LOCATION R3070
J 0
(-11000 -700);
DISPLAY 0.978723 (-11000 -700);
FORCEPROP 1 LASTPIN (-11050 -750) $PN 1
J 0
(-11038 -738);
DISPLAY 0.787234 (-11038 -738);
PAINT MONO (-11038 -738);
FORCEPROP 1 LASTPIN (-10850 -750) $PN 2
J 0
(-10888 -738);
DISPLAY 0.787234 (-10888 -738);
PAINT MONO (-10888 -738);
FORCEPROP 2 LAST CDS_LIB pure_quanta
J 0
(-10950 -750);
DISPLAY INVISIBLE (-10950 -750);
FORCEPROP 1 LAST PATH I41
J 0
(-11000 -600);
DISPLAY 0.978723 (-11000 -600);
PAINT WHITE (-11000 -600);
DISPLAY INVISIBLE (-11000 -600);
FORCEPROP 0 LAST CDS_LOCATION R3070
J 0
(-11000 -650);
DISPLAY 1.021277 (-11000 -650);
DISPLAY INVISIBLE (-11000 -650);
FORCEPROP 0 LAST $SEC 1
J 0
(-11000 -650);
DISPLAY 0.680851 (-11000 -650);
PAINT MONO (-11000 -650);
DISPLAY INVISIBLE (-11000 -650);
FORCEPROP 0 LAST CDS_SEC 1
J 0
(-11000 -650);
DISPLAY 1.021277 (-11000 -650);
DISPLAY INVISIBLE (-11000 -650);
FORCEADD MOSFET_NCH_DUAL..2
(-13425 -1025);
FORCEPROP 1 LAST PART_NUMBER BAM138K0003
J 0
(-13274 -1119);
DISPLAY 0.723404 (-13274 -1119);
PAINT BLUE (-13274 -1119);
DISPLAY INVISIBLE (-13274 -1119);
FORCEPROP 2 LAST PART_TYPE SMLF
J 0
(-13250 -950);
DISPLAY 1.021277 (-13250 -950);
FORCEPROP 1 LAST MATERIAL IC
J 0
(-13274 -1174);
DISPLAY 0.723404 (-13274 -1174);
PAINT SKYBLUE (-13274 -1174);
FORCEPROP 2 LAST VALUE PJT138K
J 0
(-13250 -1000);
DISPLAY 0.723404 (-13250 -1000);
PAINT SKYBLUE (-13250 -1000);
FORCEPROP 1 LAST LOCATION Q88
J 0
(-13274 -1049);
DISPLAY 0.723404 (-13274 -1049);
PAINT AQUA (-13274 -1049);
FORCEPROP 0 LASTPIN (-13375 -825) $PN 3
R 1
J 0
(-13385 -815);
DISPLAY 0.680851 (-13385 -815);
PAINT MONO (-13385 -815);
FORCEPROP 0 LASTPIN (-13625 -1075) $PN 5
J 2
(-13635 -1065);
DISPLAY 0.680851 (-13635 -1065);
PAINT MONO (-13635 -1065);
FORCEPROP 0 LASTPIN (-13375 -1225) $PN 4
R 1
J 2
(-13385 -1235);
DISPLAY 0.680851 (-13385 -1235);
PAINT MONO (-13385 -1235);
FORCEPROP 2 LAST CDS_LIB pure_quanta
J 0
(-13425 -1025);
DISPLAY INVISIBLE (-13425 -1025);
FORCEPROP 1 LAST CDS_LMAN_SYM_OUTLINE -150,150,150,-150
J 0
(-13425 -1025);
DISPLAY 0.468085 (-13425 -1025);
PAINT GREEN (-13425 -1025);
DISPLAY INVISIBLE (-13425 -1025);
FORCEPROP 1 LAST PATH I42
J 0
(-13275 -1175);
DISPLAY 0.723404 (-13275 -1175);
PAINT GREEN (-13275 -1175);
DISPLAY INVISIBLE (-13275 -1175);
FORCEPROP 1 LAST NEEDS_NO_SIZE TRUE
J 0
(-13275 -1134);
DISPLAY 0.468085 (-13275 -1134);
PAINT GREEN (-13275 -1134);
DISPLAY INVISIBLE (-13275 -1134);
FORCEPROP 0 LAST $SEC 2
J 0
(-13250 -900);
DISPLAY 0.680851 (-13250 -900);
PAINT MONO (-13250 -900);
DISPLAY INVISIBLE (-13250 -900);
FORCEPROP 0 LAST CDS_SEC 2
J 0
(-13250 -900);
DISPLAY 1.021277 (-13250 -900);
DISPLAY INVISIBLE (-13250 -900);
FORCEADD UNIVERSAL_POWER..1
(-6325 2475);
FORCEPROP 3 LASTPIN (-6325 2425) SIG_NAME P12V_PSU\g
J 0
(-6315 2435);
DISPLAY 0.659574 (-6315 2435);
PAINT MONO (-6315 2435);
DISPLAY INVISIBLE (-6315 2435);
FORCEPROP 1 LAST HDL_POWER P12V_PSU
J 1
(-6325 2525);
DISPLAY 0.723404 (-6325 2525);
PAINT GREEN (-6325 2525);
FORCEPROP 1 LAST PATH I47
J 0
(-6275 2500);
DISPLAY 0.872340 (-6275 2500);
PAINT AQUA (-6275 2500);
DISPLAY INVISIBLE (-6275 2500);
FORCEPROP 2 LAST CDS_LIB logical_power
J 0
(-6325 2475);
DISPLAY INVISIBLE (-6325 2475);
FORCEADD Q_LED..1
R 2
(-9125 2150);
FORCEPROP 1 LAST PART_NUMBER BEBL0172Z00
J 0
(-9225 1925);
DISPLAY 0.574468 (-9225 1925);
PAINT GREEN (-9225 1925);
DISPLAY INVISIBLE (-9225 1925);
FORCEPROP 2 LAST MANUF_PN LTST-C281TBKT-5A
J 0
(-9225 1875);
DISPLAY 0.638298 (-9225 1875);
FORCEPROP 1 LAST MATERIAL IC
J 0
(-9100 1975);
DISPLAY 0.723404 (-9100 1975);
PAINT GREEN (-9100 1975);
FORCEPROP 0 LAST PACK_TYPE SMLF
J 0
(-9225 1975);
DISPLAY 0.638298 (-9225 1975);
FORCEPROP 2 LAST COLOR LED_BLUE
J 0
(-9225 2025);
DISPLAY 0.638298 (-9225 2025);
FORCEPROP 1 LAST $LOCATION D143
J 0
(-9225 2075);
DISPLAY 0.723404 (-9225 2075);
PAINT GREEN (-9225 2075);
FORCEPROP 0 LASTPIN (-8975 2150) $PN A
J 0
(-8965 2160);
DISPLAY 0.680851 (-8965 2160);
PAINT MONO (-8965 2160);
FORCEPROP 0 LASTPIN (-9275 2150) $PN C
J 2
(-9285 2160);
DISPLAY 0.680851 (-9285 2160);
PAINT MONO (-9285 2160);
FORCEPROP 2 LAST CDS_LIB pure_quanta
J 0
(-9125 2150);
DISPLAY INVISIBLE (-9125 2150);
FORCEPROP 1 LAST PATH I49
J 2
(-9250 2230);
DISPLAY 0.723404 (-9250 2230);
PAINT GREEN (-9250 2230);
DISPLAY INVISIBLE (-9250 2230);
FORCEPROP 1 LAST NEEDS_NO_SIZE TRUE
J 2
(-9103 2172);
DISPLAY 0.468085 (-9103 2172);
PAINT GREEN (-9103 2172);
DISPLAY INVISIBLE (-9103 2172);
FORCEPROP 0 LAST CDS_LOCATION D143
J 0
(-9225 2125);
DISPLAY 1.021277 (-9225 2125);
DISPLAY INVISIBLE (-9225 2125);
FORCEPROP 0 LAST $SEC 1
J 0
(-9225 2125);
DISPLAY 0.680851 (-9225 2125);
PAINT MONO (-9225 2125);
DISPLAY INVISIBLE (-9225 2125);
FORCEPROP 0 LAST CDS_SEC 1
J 0
(-9225 2125);
DISPLAY 1.021277 (-9225 2125);
DISPLAY INVISIBLE (-9225 2125);
FORCEADD OFFPAGE..1
(-14600 3025);
PAINT AQUA (-14600 3025);
FORCEPROP 2 LAST $XR2 222 
J 0
(-15122 3025);
DISPLAY 0.638298 (-15122 3025);
PAINT MONO (-15122 3025);
FORCEPROP 2 LAST $XR1 220 
J 0
(-15002 3025);
DISPLAY 0.638298 (-15002 3025);
PAINT MONO (-15002 3025);
FORCEPROP 2 LAST $XR0 214 
J 0
(-14882 3025);
DISPLAY 0.638298 (-14882 3025);
PAINT MONO (-14882 3025);
FORCEPROP 2 LAST PATH I5
J 0
(-14850 3075);
DISPLAY 1.021277 (-14850 3075);
DISPLAY INVISIBLE (-14850 3075);
FORCEPROP 2 LAST CDS_LIB standard
J 0
(-14600 3025);
DISPLAY INVISIBLE (-14600 3025);
FORCEPROP 1 LAST OFFPAGE TRUE
J 0
(-14275 2900);
DISPLAY 0.872340 (-14275 2900);
PAINT AQUA (-14275 2900);
DISPLAY INVISIBLE (-14275 2900);
FORCEPROP 1 LAST COMMENT_BODY TRUE
J 0
(-14475 2925);
DISPLAY 0.872340 (-14475 2925);
PAINT GREEN (-14475 2925);
DISPLAY INVISIBLE (-14475 2925);
FORCEADD UNIVERSAL_GND..1
(-9400 1875);
FORCEPROP 3 LASTPIN (-9400 1925) SIG_NAME GND\g
J 0
(-9390 1935);
DISPLAY 0.659574 (-9390 1935);
PAINT MONO (-9390 1935);
DISPLAY INVISIBLE (-9390 1935);
FORCEPROP 1 LAST HDL_POWER GND
J 1
(-9375 1800);
DISPLAY 0.872340 (-9375 1800);
PAINT GREEN (-9375 1800);
DISPLAY INVISIBLE (-9375 1800);
FORCEPROP 1 LAST PATH I50
J 0
(-9325 1875);
DISPLAY 0.872340 (-9325 1875);
PAINT AQUA (-9325 1875);
DISPLAY INVISIBLE (-9325 1875);
FORCEPROP 2 LAST CDS_LIB logical_power
J 0
(-9400 1875);
DISPLAY INVISIBLE (-9400 1875);
FORCEADD UNIVERSAL_POWER..1
(-6325 3725);
FORCEPROP 3 LASTPIN (-6325 3675) SIG_NAME P12V_AUX\g
J 0
(-6315 3685);
DISPLAY 0.659574 (-6315 3685);
PAINT MONO (-6315 3685);
DISPLAY INVISIBLE (-6315 3685);
FORCEPROP 1 LAST HDL_POWER P12V_AUX
J 1
(-6325 3775);
DISPLAY 0.723404 (-6325 3775);
PAINT GREEN (-6325 3775);
FORCEPROP 1 LAST PATH I54
J 0
(-6275 3750);
DISPLAY 0.872340 (-6275 3750);
PAINT AQUA (-6275 3750);
DISPLAY INVISIBLE (-6275 3750);
FORCEPROP 2 LAST CDS_LIB logical_power
J 0
(-6325 3725);
DISPLAY INVISIBLE (-6325 3725);
FORCEADD Q_LED..1
R 2
(-9125 3400);
FORCEPROP 1 LAST PART_NUMBER BEBL0172Z00
J 0
(-9225 3175);
DISPLAY 0.574468 (-9225 3175);
PAINT GREEN (-9225 3175);
DISPLAY INVISIBLE (-9225 3175);
FORCEPROP 2 LAST COLOR LED_BLUE
J 0
(-9225 3275);
DISPLAY 0.638298 (-9225 3275);
FORCEPROP 0 LAST PACK_TYPE SMLF
J 0
(-9225 3225);
DISPLAY 0.638298 (-9225 3225);
FORCEPROP 1 LAST MATERIAL IC
J 0
(-9100 3225);
DISPLAY 0.723404 (-9100 3225);
PAINT GREEN (-9100 3225);
FORCEPROP 2 LAST MANUF_PN LTST-C281TBKT-5A
J 0
(-9225 3125);
DISPLAY 0.638298 (-9225 3125);
FORCEPROP 1 LAST $LOCATION D142
J 0
(-9225 3325);
DISPLAY 0.723404 (-9225 3325);
PAINT GREEN (-9225 3325);
FORCEPROP 0 LASTPIN (-8975 3400) $PN A
J 0
(-8965 3410);
DISPLAY 0.680851 (-8965 3410);
PAINT MONO (-8965 3410);
FORCEPROP 0 LASTPIN (-9275 3400) $PN C
J 2
(-9285 3410);
DISPLAY 0.680851 (-9285 3410);
PAINT MONO (-9285 3410);
FORCEPROP 1 LAST PATH I58
J 2
(-9250 3480);
DISPLAY 0.723404 (-9250 3480);
PAINT GREEN (-9250 3480);
DISPLAY INVISIBLE (-9250 3480);
FORCEPROP 1 LAST NEEDS_NO_SIZE TRUE
J 2
(-9103 3422);
DISPLAY 0.468085 (-9103 3422);
PAINT GREEN (-9103 3422);
DISPLAY INVISIBLE (-9103 3422);
FORCEPROP 2 LAST CDS_LIB pure_quanta
J 0
(-9125 3400);
DISPLAY INVISIBLE (-9125 3400);
FORCEPROP 0 LAST CDS_LOCATION D142
J 0
(-9225 3375);
DISPLAY 1.021277 (-9225 3375);
DISPLAY INVISIBLE (-9225 3375);
FORCEPROP 0 LAST $SEC 1
J 0
(-9225 3375);
DISPLAY 0.680851 (-9225 3375);
PAINT MONO (-9225 3375);
DISPLAY INVISIBLE (-9225 3375);
FORCEPROP 0 LAST CDS_SEC 1
J 0
(-9225 3375);
DISPLAY 1.021277 (-9225 3375);
DISPLAY INVISIBLE (-9225 3375);
FORCEADD UNIVERSAL_GND..1
(-9400 3125);
FORCEPROP 3 LASTPIN (-9400 3175) SIG_NAME GND\g
J 0
(-9390 3185);
DISPLAY 0.659574 (-9390 3185);
PAINT MONO (-9390 3185);
DISPLAY INVISIBLE (-9390 3185);
FORCEPROP 1 LAST PATH I59
J 0
(-9325 3125);
DISPLAY 0.872340 (-9325 3125);
PAINT AQUA (-9325 3125);
DISPLAY INVISIBLE (-9325 3125);
FORCEPROP 2 LAST CDS_LIB logical_power
J 0
(-9400 3125);
DISPLAY INVISIBLE (-9400 3125);
FORCEPROP 1 LAST HDL_POWER GND
J 1
(-9375 3050);
DISPLAY 0.872340 (-9375 3050);
PAINT GREEN (-9375 3050);
DISPLAY INVISIBLE (-9375 3050);
FORCEADD Q_RES..1
(-8400 2150);
FORCEPROP 1 LAST PART_NUMBER CS15602FB03
J 0
(-8400 2075);
DISPLAY 0.638298 (-8400 2075);
DISPLAY INVISIBLE (-8400 2075);
FORCEPROP 1 LAST WATTAGE 1/16W
J 2
(-8525 2025);
DISPLAY 0.638298 (-8525 2025);
FORCEPROP 1 LAST MATERIAL CHIP
J 0
(-8500 2025);
DISPLAY 0.638298 (-8500 2025);
FORCEPROP 1 LAST VALUE 560
J 2
(-8525 2075);
DISPLAY 0.638298 (-8525 2075);
FORCEPROP 1 LAST TOLERANCE 1%
J 0
(-8500 2075);
DISPLAY 0.638298 (-8500 2075);
FORCEPROP 1 LAST PACK_TYPE 0402LF
J 0
(-8250 2025);
DISPLAY 0.638298 (-8250 2025);
FORCEPROP 1 LAST $LOCATION R4703
J 0
(-8625 2150);
DISPLAY 0.787234 (-8625 2150);
FORCEPROP 1 LASTPIN (-8500 2150) $PN 1
J 0
(-8488 2162);
DISPLAY 0.787234 (-8488 2162);
PAINT MONO (-8488 2162);
FORCEPROP 1 LASTPIN (-8300 2150) $PN 2
J 0
(-8338 2162);
DISPLAY 0.787234 (-8338 2162);
PAINT MONO (-8338 2162);
FORCEPROP 1 LAST PATH I61
J 0
(-8450 2300);
DISPLAY 0.978723 (-8450 2300);
PAINT WHITE (-8450 2300);
DISPLAY INVISIBLE (-8450 2300);
FORCEPROP 2 LAST CDS_LIB pure_quanta
J 0
(-8400 2150);
DISPLAY INVISIBLE (-8400 2150);
FORCEPROP 0 LAST CDS_LOCATION R4703
J 0
(-8525 2200);
DISPLAY 1.021277 (-8525 2200);
DISPLAY INVISIBLE (-8525 2200);
FORCEPROP 0 LAST $SEC 1
J 0
(-8525 2200);
DISPLAY 0.680851 (-8525 2200);
PAINT MONO (-8525 2200);
DISPLAY INVISIBLE (-8525 2200);
FORCEPROP 0 LAST CDS_SEC 1
J 0
(-8525 2200);
DISPLAY 1.021277 (-8525 2200);
DISPLAY INVISIBLE (-8525 2200);
FORCEADD Q_RES..1
(-7700 2150);
FORCEPROP 1 LAST PART_NUMBER CS15602FB03
J 0
(-7700 2075);
DISPLAY 0.638298 (-7700 2075);
DISPLAY INVISIBLE (-7700 2075);
FORCEPROP 1 LAST TOLERANCE 1%
J 0
(-7800 2075);
DISPLAY 0.638298 (-7800 2075);
FORCEPROP 1 LAST VALUE 560
J 2
(-7825 2075);
DISPLAY 0.638298 (-7825 2075);
FORCEPROP 1 LAST WATTAGE 1/16W
J 2
(-7825 2025);
DISPLAY 0.638298 (-7825 2025);
FORCEPROP 1 LAST PACK_TYPE 0402LF
J 0
(-7550 2025);
DISPLAY 0.638298 (-7550 2025);
FORCEPROP 1 LAST MATERIAL CHIP
J 0
(-7800 2025);
DISPLAY 0.638298 (-7800 2025);
FORCEPROP 1 LAST $LOCATION R4705
J 0
(-7925 2150);
DISPLAY 0.787234 (-7925 2150);
FORCEPROP 1 LASTPIN (-7800 2150) $PN 1
J 0
(-7788 2162);
DISPLAY 0.787234 (-7788 2162);
PAINT MONO (-7788 2162);
FORCEPROP 1 LASTPIN (-7600 2150) $PN 2
J 0
(-7638 2162);
DISPLAY 0.787234 (-7638 2162);
PAINT MONO (-7638 2162);
FORCEPROP 1 LAST PATH I62
J 0
(-7750 2300);
DISPLAY 0.978723 (-7750 2300);
PAINT WHITE (-7750 2300);
DISPLAY INVISIBLE (-7750 2300);
FORCEPROP 2 LAST CDS_LIB pure_quanta
J 0
(-7700 2150);
DISPLAY INVISIBLE (-7700 2150);
FORCEPROP 0 LAST CDS_LOCATION R4705
J 0
(-7825 2200);
DISPLAY 1.021277 (-7825 2200);
DISPLAY INVISIBLE (-7825 2200);
FORCEPROP 0 LAST $SEC 1
J 0
(-7825 2200);
DISPLAY 0.680851 (-7825 2200);
PAINT MONO (-7825 2200);
DISPLAY INVISIBLE (-7825 2200);
FORCEPROP 0 LAST CDS_SEC 1
J 0
(-7825 2200);
DISPLAY 1.021277 (-7825 2200);
DISPLAY INVISIBLE (-7825 2200);
FORCEADD Q_RES..1
(-6825 2150);
FORCEPROP 1 LAST PART_NUMBER CS15602FB03
J 0
(-6825 2075);
DISPLAY 0.638298 (-6825 2075);
DISPLAY INVISIBLE (-6825 2075);
FORCEPROP 1 LAST VALUE 560
J 2
(-6950 2075);
DISPLAY 0.638298 (-6950 2075);
FORCEPROP 1 LAST WATTAGE 1/16W
J 2
(-6950 2025);
DISPLAY 0.638298 (-6950 2025);
FORCEPROP 1 LAST MATERIAL CHIP
J 0
(-6925 2025);
DISPLAY 0.638298 (-6925 2025);
FORCEPROP 1 LAST TOLERANCE 1%
J 0
(-6925 2075);
DISPLAY 0.638298 (-6925 2075);
FORCEPROP 1 LAST PACK_TYPE 0402LF
J 0
(-6675 2025);
DISPLAY 0.638298 (-6675 2025);
FORCEPROP 1 LAST $LOCATION R4707
J 0
(-7075 2150);
DISPLAY 0.787234 (-7075 2150);
FORCEPROP 1 LASTPIN (-6925 2150) $PN 1
J 0
(-6913 2162);
DISPLAY 0.787234 (-6913 2162);
PAINT MONO (-6913 2162);
FORCEPROP 1 LASTPIN (-6725 2150) $PN 2
J 0
(-6763 2162);
DISPLAY 0.787234 (-6763 2162);
PAINT MONO (-6763 2162);
FORCEPROP 2 LAST CDS_LIB pure_quanta
J 0
(-6825 2150);
DISPLAY INVISIBLE (-6825 2150);
FORCEPROP 1 LAST PATH I63
J 0
(-6875 2300);
DISPLAY 0.978723 (-6875 2300);
PAINT WHITE (-6875 2300);
DISPLAY INVISIBLE (-6875 2300);
FORCEPROP 0 LAST CDS_LOCATION R4707
J 0
(-6975 2200);
DISPLAY 1.021277 (-6975 2200);
DISPLAY INVISIBLE (-6975 2200);
FORCEPROP 0 LAST $SEC 1
J 0
(-6975 2200);
DISPLAY 0.680851 (-6975 2200);
PAINT MONO (-6975 2200);
DISPLAY INVISIBLE (-6975 2200);
FORCEPROP 0 LAST CDS_SEC 1
J 0
(-6975 2200);
DISPLAY 1.021277 (-6975 2200);
DISPLAY INVISIBLE (-6975 2200);
FORCEADD Q_RES..1
(-8400 3400);
FORCEPROP 1 LAST PART_NUMBER CS15602FB03
J 0
(-8400 3325);
DISPLAY 0.638298 (-8400 3325);
DISPLAY INVISIBLE (-8400 3325);
FORCEPROP 1 LAST PACK_TYPE 0402LF
J 0
(-8250 3275);
DISPLAY 0.638298 (-8250 3275);
FORCEPROP 1 LAST MATERIAL CHIP
J 0
(-8500 3275);
DISPLAY 0.638298 (-8500 3275);
FORCEPROP 1 LAST TOLERANCE 1%
J 0
(-8500 3325);
DISPLAY 0.638298 (-8500 3325);
FORCEPROP 1 LAST WATTAGE 1/16W
J 2
(-8525 3275);
DISPLAY 0.638298 (-8525 3275);
FORCEPROP 1 LAST VALUE 560
J 2
(-8525 3325);
DISPLAY 0.638298 (-8525 3325);
FORCEPROP 1 LAST $LOCATION R4702
J 0
(-8625 3400);
DISPLAY 0.787234 (-8625 3400);
FORCEPROP 1 LASTPIN (-8500 3400) $PN 1
J 0
(-8488 3412);
DISPLAY 0.787234 (-8488 3412);
PAINT MONO (-8488 3412);
FORCEPROP 1 LASTPIN (-8300 3400) $PN 2
J 0
(-8338 3412);
DISPLAY 0.787234 (-8338 3412);
PAINT MONO (-8338 3412);
FORCEPROP 2 LAST CDS_LIB pure_quanta
J 0
(-8400 3400);
DISPLAY INVISIBLE (-8400 3400);
FORCEPROP 1 LAST PATH I64
J 0
(-8450 3550);
DISPLAY 0.978723 (-8450 3550);
PAINT WHITE (-8450 3550);
DISPLAY INVISIBLE (-8450 3550);
FORCEPROP 0 LAST CDS_LOCATION R4702
J 0
(-8525 3450);
DISPLAY 1.021277 (-8525 3450);
DISPLAY INVISIBLE (-8525 3450);
FORCEPROP 0 LAST $SEC 1
J 0
(-8525 3450);
DISPLAY 0.680851 (-8525 3450);
PAINT MONO (-8525 3450);
DISPLAY INVISIBLE (-8525 3450);
FORCEPROP 0 LAST CDS_SEC 1
J 0
(-8525 3450);
DISPLAY 1.021277 (-8525 3450);
DISPLAY INVISIBLE (-8525 3450);
FORCEADD Q_RES..1
(-7725 3400);
FORCEPROP 1 LAST PART_NUMBER CS15602FB03
J 0
(-7725 3325);
DISPLAY 0.638298 (-7725 3325);
DISPLAY INVISIBLE (-7725 3325);
FORCEPROP 1 LAST VALUE 560
J 2
(-7850 3325);
DISPLAY 0.638298 (-7850 3325);
FORCEPROP 1 LAST WATTAGE 1/16W
J 2
(-7850 3275);
DISPLAY 0.638298 (-7850 3275);
FORCEPROP 1 LAST MATERIAL CHIP
J 0
(-7825 3275);
DISPLAY 0.638298 (-7825 3275);
FORCEPROP 1 LAST PACK_TYPE 0402LF
J 0
(-7575 3275);
DISPLAY 0.638298 (-7575 3275);
FORCEPROP 1 LAST TOLERANCE 1%
J 0
(-7825 3325);
DISPLAY 0.638298 (-7825 3325);
FORCEPROP 1 LAST $LOCATION R4704
J 0
(-7950 3400);
DISPLAY 0.787234 (-7950 3400);
FORCEPROP 1 LASTPIN (-7825 3400) $PN 1
J 0
(-7813 3412);
DISPLAY 0.787234 (-7813 3412);
PAINT MONO (-7813 3412);
FORCEPROP 1 LASTPIN (-7625 3400) $PN 2
J 0
(-7663 3412);
DISPLAY 0.787234 (-7663 3412);
PAINT MONO (-7663 3412);
FORCEPROP 2 LAST CDS_LIB pure_quanta
J 0
(-7725 3400);
DISPLAY INVISIBLE (-7725 3400);
FORCEPROP 1 LAST PATH I65
J 0
(-7775 3550);
DISPLAY 0.978723 (-7775 3550);
PAINT WHITE (-7775 3550);
DISPLAY INVISIBLE (-7775 3550);
FORCEPROP 0 LAST CDS_LOCATION R4704
J 0
(-7875 3450);
DISPLAY 1.021277 (-7875 3450);
DISPLAY INVISIBLE (-7875 3450);
FORCEPROP 0 LAST $SEC 1
J 0
(-7875 3450);
DISPLAY 0.680851 (-7875 3450);
PAINT MONO (-7875 3450);
DISPLAY INVISIBLE (-7875 3450);
FORCEPROP 0 LAST CDS_SEC 1
J 0
(-7875 3450);
DISPLAY 1.021277 (-7875 3450);
DISPLAY INVISIBLE (-7875 3450);
FORCEADD Q_RES..1
(-6825 3400);
FORCEPROP 1 LAST PART_NUMBER CS15602FB03
J 0
(-6825 3325);
DISPLAY 0.638298 (-6825 3325);
DISPLAY INVISIBLE (-6825 3325);
FORCEPROP 1 LAST WATTAGE 1/16W
J 2
(-6950 3275);
DISPLAY 0.638298 (-6950 3275);
FORCEPROP 1 LAST PACK_TYPE 0402LF
J 0
(-6675 3275);
DISPLAY 0.638298 (-6675 3275);
FORCEPROP 1 LAST TOLERANCE 1%
J 0
(-6925 3325);
DISPLAY 0.638298 (-6925 3325);
FORCEPROP 1 LAST VALUE 560
J 2
(-6950 3325);
DISPLAY 0.638298 (-6950 3325);
FORCEPROP 1 LAST MATERIAL CHIP
J 0
(-6925 3275);
DISPLAY 0.638298 (-6925 3275);
FORCEPROP 1 LAST $LOCATION R4706
J 0
(-7075 3400);
DISPLAY 0.787234 (-7075 3400);
FORCEPROP 1 LASTPIN (-6925 3400) $PN 1
J 0
(-6913 3412);
DISPLAY 0.787234 (-6913 3412);
PAINT MONO (-6913 3412);
FORCEPROP 1 LASTPIN (-6725 3400) $PN 2
J 0
(-6763 3412);
DISPLAY 0.787234 (-6763 3412);
PAINT MONO (-6763 3412);
FORCEPROP 2 LAST CDS_LIB pure_quanta
J 0
(-6825 3400);
DISPLAY INVISIBLE (-6825 3400);
FORCEPROP 1 LAST PATH I66
J 0
(-6875 3550);
DISPLAY 0.978723 (-6875 3550);
PAINT WHITE (-6875 3550);
DISPLAY INVISIBLE (-6875 3550);
FORCEPROP 0 LAST CDS_LOCATION R4706
J 0
(-7000 3450);
DISPLAY 1.021277 (-7000 3450);
DISPLAY INVISIBLE (-7000 3450);
FORCEPROP 0 LAST $SEC 1
J 0
(-7000 3450);
DISPLAY 0.680851 (-7000 3450);
PAINT MONO (-7000 3450);
DISPLAY INVISIBLE (-7000 3450);
FORCEPROP 0 LAST CDS_SEC 1
J 0
(-7000 3450);
DISPLAY 1.021277 (-7000 3450);
DISPLAY INVISIBLE (-7000 3450);
FORCEADD Q_LED..1
R 2
(-7500 425);
FORCEPROP 1 LAST PART_NUMBER BEYL0159Z00
J 2
(-7400 560);
DISPLAY 0.723404 (-7400 560);
PAINT GREEN (-7400 560);
DISPLAY INVISIBLE (-7400 560);
FORCEPROP 1 LAST MATERIAL IC
J 2
(-7400 505);
DISPLAY 0.723404 (-7400 505);
PAINT GREEN (-7400 505);
FORCEPROP 2 LAST COLOR LED_YELLOW
J 2
(-7400 750);
DISPLAY 0.808511 (-7400 750);
FORCEPROP 2 LAST PACK_TYPE SMLF
J 2
(-7400 650);
DISPLAY 0.808511 (-7400 650);
FORCEPROP 2 LAST MANUF_PN LTST-C190KSKT-P
J 2
(-7400 700);
DISPLAY 0.808511 (-7400 700);
FORCEPROP 1 LAST $LOCATION D144
J 2
(-7400 610);
DISPLAY 0.723404 (-7400 610);
PAINT GREEN (-7400 610);
FORCEPROP 0 LASTPIN (-7350 425) $PN A
J 0
(-7340 435);
DISPLAY 0.680851 (-7340 435);
PAINT MONO (-7340 435);
FORCEPROP 0 LASTPIN (-7650 425) $PN C
J 2
(-7660 435);
DISPLAY 0.680851 (-7660 435);
PAINT MONO (-7660 435);
FORCEPROP 2 LAST CDS_LIB pure_quanta
J 2
(-7500 425);
DISPLAY INVISIBLE (-7500 425);
FORCEPROP 1 LAST PATH I67
J 2
(-7625 505);
DISPLAY 0.723404 (-7625 505);
PAINT GREEN (-7625 505);
DISPLAY INVISIBLE (-7625 505);
FORCEPROP 1 LAST NEEDS_NO_SIZE TRUE
J 2
(-7500 425);
DISPLAY 0.468085 (-7500 425);
PAINT GREEN (-7500 425);
DISPLAY INVISIBLE (-7500 425);
FORCEPROP 0 LAST CDS_LOCATION D144
J 0
(-7400 800);
DISPLAY 1.021277 (-7400 800);
DISPLAY INVISIBLE (-7400 800);
FORCEPROP 0 LAST $SEC 1
J 0
(-7400 800);
DISPLAY 0.680851 (-7400 800);
PAINT MONO (-7400 800);
DISPLAY INVISIBLE (-7400 800);
FORCEPROP 0 LAST CDS_SEC 1
J 0
(-7400 800);
DISPLAY 1.021277 (-7400 800);
DISPLAY INVISIBLE (-7400 800);
FORCEADD Q_RES..1
(-6525 425);
FORCEPROP 1 LAST PART_NUMBER CS12492FB02
J 0
(-6575 525);
DISPLAY 0.787234 (-6575 525);
DISPLAY INVISIBLE (-6575 525);
FORCEPROP 1 LAST VALUE 249
J 2
(-6525 325);
DISPLAY 0.787234 (-6525 325);
FORCEPROP 1 LAST WATTAGE 1/16W
J 2
(-6525 275);
DISPLAY 0.787234 (-6525 275);
FORCEPROP 1 LAST PACK_TYPE 0402LF
J 0
(-6250 275);
DISPLAY 0.787234 (-6250 275);
FORCEPROP 1 LAST TOLERANCE 1%
J 0
(-6500 325);
DISPLAY 0.787234 (-6500 325);
FORCEPROP 1 LAST MATERIAL CHIP
J 0
(-6500 275);
DISPLAY 0.787234 (-6500 275);
FORCEPROP 1 LAST $LOCATION R4711
J 0
(-6575 475);
DISPLAY 0.978723 (-6575 475);
FORCEPROP 1 LASTPIN (-6625 425) $PN 1
J 0
(-6613 437);
DISPLAY 0.787234 (-6613 437);
PAINT MONO (-6613 437);
FORCEPROP 1 LASTPIN (-6425 425) $PN 2
J 0
(-6463 437);
DISPLAY 0.787234 (-6463 437);
PAINT MONO (-6463 437);
FORCEPROP 2 LAST CDS_LIB pure_quanta
J 0
(-6525 425);
DISPLAY INVISIBLE (-6525 425);
FORCEPROP 1 LAST PATH I68
J 0
(-6575 575);
DISPLAY 0.978723 (-6575 575);
PAINT WHITE (-6575 575);
DISPLAY INVISIBLE (-6575 575);
FORCEPROP 0 LAST CDS_LOCATION R4711
J 0
(-6575 575);
DISPLAY 1.021277 (-6575 575);
DISPLAY INVISIBLE (-6575 575);
FORCEPROP 0 LAST $SEC 1
J 0
(-6575 575);
DISPLAY 0.680851 (-6575 575);
PAINT MONO (-6575 575);
DISPLAY INVISIBLE (-6575 575);
FORCEPROP 0 LAST CDS_SEC 1
J 0
(-6575 575);
DISPLAY 1.021277 (-6575 575);
DISPLAY INVISIBLE (-6575 575);
FORCEADD MOSFET_NCH_DUAL..1
(-9075 -225);
FORCEPROP 1 LAST PART_NUMBER BAM138K0003
J 0
(-8924 -311);
DISPLAY 0.723404 (-8924 -311);
PAINT GREEN (-8924 -311);
DISPLAY INVISIBLE (-8924 -311);
FORCEPROP 1 LAST MATERIAL IC
J 0
(-8924 -376);
DISPLAY 0.723404 (-8924 -376);
PAINT GREEN (-8924 -376);
FORCEPROP 2 LAST PART_TYPE SMLF
J 0
(-8900 -150);
DISPLAY 1.021277 (-8900 -150);
FORCEPROP 2 LAST VALUE PJT138K
J 0
(-8900 -200);
DISPLAY 1.021277 (-8900 -200);
FORCEPROP 1 LAST $LOCATION Q150
J 0
(-8924 -251);
DISPLAY 0.723404 (-8924 -251);
PAINT GREEN (-8924 -251);
FORCEPROP 0 LASTPIN (-9025 -25) $PN 6
R 1
J 0
(-9035 -15);
DISPLAY 0.680851 (-9035 -15);
PAINT MONO (-9035 -15);
FORCEPROP 0 LASTPIN (-9275 -275) $PN 2
J 2
(-9285 -265);
DISPLAY 0.680851 (-9285 -265);
PAINT MONO (-9285 -265);
FORCEPROP 0 LASTPIN (-9025 -425) $PN 1
R 1
J 2
(-9035 -435);
DISPLAY 0.680851 (-9035 -435);
PAINT MONO (-9035 -435);
FORCEPROP 2 LAST CDS_LIB pure_quanta
J 0
(-9075 -225);
DISPLAY INVISIBLE (-9075 -225);
FORCEPROP 1 LAST PATH I69
J 0
(-9075 -225);
DISPLAY 0.723404 (-9075 -225);
PAINT GREEN (-9075 -225);
DISPLAY INVISIBLE (-9075 -225);
FORCEPROP 1 LAST CDS_LMAN_SYM_OUTLINE -150,150,150,-150
J 0
(-9075 -225);
DISPLAY 0.468085 (-9075 -225);
PAINT GREEN (-9075 -225);
DISPLAY INVISIBLE (-9075 -225);
FORCEPROP 1 LAST NEEDS_NO_SIZE TRUE
J 0
(-9075 -226);
DISPLAY 0.468085 (-9075 -226);
PAINT GREEN (-9075 -226);
DISPLAY INVISIBLE (-9075 -226);
FORCEPROP 0 LAST CDS_LOCATION Q150
J 0
(-8900 -100);
DISPLAY 1.021277 (-8900 -100);
DISPLAY INVISIBLE (-8900 -100);
FORCEPROP 0 LAST $SEC 1
J 0
(-8900 -100);
DISPLAY 0.680851 (-8900 -100);
PAINT MONO (-8900 -100);
DISPLAY INVISIBLE (-8900 -100);
FORCEPROP 0 LAST CDS_SEC 1
J 0
(-8900 -100);
DISPLAY 1.021277 (-8900 -100);
DISPLAY INVISIBLE (-8900 -100);
FORCEADD UNIVERSAL_POWER..1
(-6150 725);
FORCEPROP 3 LASTPIN (-6150 675) SIG_NAME P3V3_AUX\g
J 0
(-6140 685);
DISPLAY 0.659574 (-6140 685);
PAINT MONO (-6140 685);
DISPLAY INVISIBLE (-6140 685);
FORCEPROP 1 LAST HDL_POWER P3V3_AUX
J 1
(-6150 775);
DISPLAY 0.723404 (-6150 775);
PAINT GREEN (-6150 775);
FORCEPROP 2 LAST CDS_LIB logical_power
J 0
(-6150 725);
DISPLAY INVISIBLE (-6150 725);
FORCEPROP 1 LAST PATH I71
J 0
(-6100 750);
DISPLAY 0.872340 (-6100 750);
PAINT AQUA (-6100 750);
DISPLAY INVISIBLE (-6100 750);
FORCEADD MOSFET_NCH_DUAL..2
(-8025 150);
FORCEPROP 1 LAST PART_NUMBER BAM138K0003
J 0
(-7874 56);
DISPLAY 0.723404 (-7874 56);
PAINT BLUE (-7874 56);
DISPLAY INVISIBLE (-7874 56);
FORCEPROP 2 LAST PART_TYPE SMLF
J 0
(-7850 225);
DISPLAY 1.021277 (-7850 225);
FORCEPROP 1 LAST MATERIAL IC
J 0
(-7874 1);
DISPLAY 0.723404 (-7874 1);
PAINT SKYBLUE (-7874 1);
FORCEPROP 2 LAST VALUE PJT138K
J 0
(-7850 175);
DISPLAY 0.723404 (-7850 175);
PAINT SKYBLUE (-7850 175);
FORCEPROP 1 LAST $LOCATION Q150
J 0
(-7874 126);
DISPLAY 0.723404 (-7874 126);
PAINT AQUA (-7874 126);
FORCEPROP 0 LASTPIN (-7975 350) $PN 3
R 1
J 0
(-7985 360);
DISPLAY 0.680851 (-7985 360);
PAINT MONO (-7985 360);
FORCEPROP 0 LASTPIN (-8225 100) $PN 5
J 2
(-8235 110);
DISPLAY 0.680851 (-8235 110);
PAINT MONO (-8235 110);
FORCEPROP 0 LASTPIN (-7975 -50) $PN 4
R 1
J 2
(-7985 -60);
DISPLAY 0.680851 (-7985 -60);
PAINT MONO (-7985 -60);
FORCEPROP 2 LAST CDS_LIB pure_quanta
J 0
(-8025 150);
DISPLAY INVISIBLE (-8025 150);
FORCEPROP 1 LAST PATH I72
J 0
(-7875 0);
DISPLAY 0.723404 (-7875 0);
PAINT GREEN (-7875 0);
DISPLAY INVISIBLE (-7875 0);
FORCEPROP 1 LAST CDS_LMAN_SYM_OUTLINE -150,150,150,-150
J 0
(-8025 150);
DISPLAY 0.468085 (-8025 150);
PAINT GREEN (-8025 150);
DISPLAY INVISIBLE (-8025 150);
FORCEPROP 1 LAST NEEDS_NO_SIZE TRUE
J 0
(-7875 41);
DISPLAY 0.468085 (-7875 41);
PAINT GREEN (-7875 41);
DISPLAY INVISIBLE (-7875 41);
FORCEPROP 0 LAST CDS_LOCATION Q150
J 0
(-7850 275);
DISPLAY 1.021277 (-7850 275);
DISPLAY INVISIBLE (-7850 275);
FORCEPROP 0 LAST $SEC 2
J 0
(-7850 275);
DISPLAY 0.680851 (-7850 275);
PAINT MONO (-7850 275);
DISPLAY INVISIBLE (-7850 275);
FORCEPROP 0 LAST CDS_SEC 2
J 0
(-7850 275);
DISPLAY 1.021277 (-7850 275);
DISPLAY INVISIBLE (-7850 275);
FORCEADD UNIVERSAL_GND..1
(-7975 -300);
FORCEPROP 3 LASTPIN (-7975 -250) SIG_NAME GND\g
J 0
(-7965 -240);
DISPLAY 0.659574 (-7965 -240);
PAINT MONO (-7965 -240);
DISPLAY INVISIBLE (-7965 -240);
FORCEPROP 2 LAST CDS_LIB logical_power
J 0
(-7975 -300);
DISPLAY INVISIBLE (-7975 -300);
FORCEPROP 1 LAST PATH I73
J 0
(-7900 -300);
DISPLAY 0.872340 (-7900 -300);
PAINT AQUA (-7900 -300);
DISPLAY INVISIBLE (-7900 -300);
FORCEPROP 1 LAST HDL_POWER GND
J 1
(-7950 -375);
DISPLAY 0.872340 (-7950 -375);
PAINT GREEN (-7950 -375);
DISPLAY INVISIBLE (-7950 -375);
FORCEADD Q_RES..2
(-9025 425);
FORCEPROP 1 LAST PART_NUMBER CS24702JB10
J 0
(-8985 250);
DISPLAY 0.638298 (-8985 250);
DISPLAY INVISIBLE (-8985 250);
FORCEPROP 1 LAST WATTAGE 1/16W
J 0
(-8985 400);
DISPLAY 0.638298 (-8985 400);
FORCEPROP 1 LAST PACK_TYPE 0402LF
J 0
(-8985 300);
DISPLAY 0.638298 (-8985 300);
FORCEPROP 1 LAST MATERIAL CHIP
J 0
(-8985 350);
DISPLAY 0.638298 (-8985 350);
FORCEPROP 1 LAST VALUE 4.7K
J 0
(-8980 500);
DISPLAY 0.638298 (-8980 500);
FORCEPROP 1 LAST TOLERANCE 5%
J 0
(-8980 450);
DISPLAY 0.638298 (-8980 450);
FORCEPROP 1 LAST $LOCATION R4710
J 0
(-8980 550);
DISPLAY 0.978723 (-8980 550);
FORCEPROP 1 LASTPIN (-9025 525) $PN 1
J 0
(-9020 487);
DISPLAY 0.787234 (-9020 487);
PAINT MONO (-9020 487);
FORCEPROP 1 LASTPIN (-9025 325) $PN 2
J 0
(-9020 335);
DISPLAY 0.787234 (-9020 335);
PAINT MONO (-9020 335);
FORCEPROP 2 LAST CDS_LIB pure_quanta
J 0
(-9025 425);
DISPLAY INVISIBLE (-9025 425);
FORCEPROP 1 LAST PATH I74
J 0
(-8975 600);
DISPLAY 0.978723 (-8975 600);
PAINT WHITE (-8975 600);
DISPLAY INVISIBLE (-8975 600);
FORCEPROP 0 LAST CDS_LOCATION R4710
J 0
(-8975 600);
DISPLAY 1.021277 (-8975 600);
DISPLAY INVISIBLE (-8975 600);
FORCEPROP 0 LAST $SEC 1
J 0
(-8975 600);
DISPLAY 0.680851 (-8975 600);
PAINT MONO (-8975 600);
DISPLAY INVISIBLE (-8975 600);
FORCEPROP 0 LAST CDS_SEC 1
J 0
(-8975 600);
DISPLAY 1.021277 (-8975 600);
DISPLAY INVISIBLE (-8975 600);
FORCEADD UNIVERSAL_POWER..1
(-9025 725);
FORCEPROP 3 LASTPIN (-9025 675) SIG_NAME P3V3_AUX\g
J 0
(-9015 685);
DISPLAY 0.659574 (-9015 685);
PAINT MONO (-9015 685);
DISPLAY INVISIBLE (-9015 685);
FORCEPROP 1 LAST HDL_POWER P3V3_AUX
J 1
(-9025 775);
DISPLAY 0.723404 (-9025 775);
PAINT GREEN (-9025 775);
FORCEPROP 2 LAST CDS_LIB logical_power
J 0
(-9025 725);
DISPLAY INVISIBLE (-9025 725);
FORCEPROP 1 LAST PATH I75
J 0
(-8975 750);
DISPLAY 0.872340 (-8975 750);
PAINT AQUA (-8975 750);
DISPLAY INVISIBLE (-8975 750);
FORCEADD UNIVERSAL_GND..1
(-9025 -675);
FORCEPROP 3 LASTPIN (-9025 -625) SIG_NAME GND\g
J 0
(-9015 -615);
DISPLAY 0.659574 (-9015 -615);
PAINT MONO (-9015 -615);
DISPLAY INVISIBLE (-9015 -615);
FORCEPROP 1 LAST HDL_POWER GND
J 1
(-9000 -750);
DISPLAY 0.872340 (-9000 -750);
PAINT GREEN (-9000 -750);
DISPLAY INVISIBLE (-9000 -750);
FORCEPROP 1 LAST PATH I76
J 0
(-8950 -675);
DISPLAY 0.872340 (-8950 -675);
PAINT AQUA (-8950 -675);
DISPLAY INVISIBLE (-8950 -675);
FORCEPROP 2 LAST CDS_LIB logical_power
J 0
(-9025 -675);
DISPLAY INVISIBLE (-9025 -675);
FORCEADD OFFPAGE..1
(-9900 -275);
PAINT AQUA (-9900 -275);
FORCEPROP 2 LAST $XR0 242 
J 0
(-10182 -275);
DISPLAY 0.638298 (-10182 -275);
PAINT MONO (-10182 -275);
FORCEPROP 2 LAST CDS_LIB standard
J 0
(-9900 -275);
DISPLAY INVISIBLE (-9900 -275);
FORCEPROP 2 LAST PATH I77
J 0
(-9850 -200);
DISPLAY 1.021277 (-9850 -200);
DISPLAY INVISIBLE (-9850 -200);
FORCEPROP 1 LAST COMMENT_BODY TRUE
J 0
(-9775 -375);
DISPLAY 0.872340 (-9775 -375);
PAINT GREEN (-9775 -375);
DISPLAY INVISIBLE (-9775 -375);
FORCEPROP 1 LAST OFFPAGE TRUE
J 0
(-9575 -400);
DISPLAY 0.872340 (-9575 -400);
PAINT AQUA (-9575 -400);
DISPLAY INVISIBLE (-9575 -400);
FORCEADD MOSFET_NCH_DUAL..1
(-13450 425);
FORCEPROP 1 LAST PART_NUMBER BAM138K0003
J 0
(-13299 339);
DISPLAY 0.723404 (-13299 339);
PAINT GREEN (-13299 339);
DISPLAY INVISIBLE (-13299 339);
FORCEPROP 2 LAST PART_TYPE SMLF
J 0
(-13275 500);
DISPLAY 1.021277 (-13275 500);
FORCEPROP 2 LAST VALUE PJT138K
J 0
(-13275 450);
DISPLAY 1.021277 (-13275 450);
FORCEPROP 1 LAST MATERIAL IC
J 0
(-13299 274);
DISPLAY 0.723404 (-13299 274);
PAINT GREEN (-13299 274);
FORCEPROP 1 LAST LOCATION Q88
J 0
(-13299 399);
DISPLAY 0.723404 (-13299 399);
PAINT GREEN (-13299 399);
FORCEPROP 0 LASTPIN (-13400 625) $PN 6
R 1
J 0
(-13410 635);
DISPLAY 0.808511 (-13410 635);
FORCEPROP 0 LASTPIN (-13650 375) $PN 2
J 2
(-13660 385);
DISPLAY 0.808511 (-13660 385);
FORCEPROP 0 LASTPIN (-13400 225) $PN 1
R 1
J 2
(-13410 215);
DISPLAY 0.808511 (-13410 215);
FORCEPROP 1 LAST CDS_LMAN_SYM_OUTLINE -150,150,150,-150
J 0
(-13450 425);
DISPLAY 0.468085 (-13450 425);
PAINT GREEN (-13450 425);
DISPLAY INVISIBLE (-13450 425);
FORCEPROP 2 LAST CDS_LIB pure_quanta
J 0
(-13450 425);
DISPLAY INVISIBLE (-13450 425);
FORCEPROP 1 LAST PATH I8
J 0
(-13450 425);
DISPLAY 0.723404 (-13450 425);
PAINT GREEN (-13450 425);
DISPLAY INVISIBLE (-13450 425);
FORCEPROP 1 LAST NEEDS_NO_SIZE TRUE
J 0
(-13450 424);
DISPLAY 0.468085 (-13450 424);
PAINT GREEN (-13450 424);
DISPLAY INVISIBLE (-13450 424);
FORCEPROP 0 LAST $SEC 1
J 0
(-13275 550);
DISPLAY INVISIBLE (-13275 550);
FORCEPROP 0 LAST CDS_SEC 1
J 0
(-13275 550);
DISPLAY INVISIBLE (-13275 550);
FORCEADD UNIVERSAL_GND..1
(-13400 75);
FORCEPROP 3 LASTPIN (-13400 125) SIG_NAME GND\g
J 0
(-13390 135);
DISPLAY 0.659574 (-13390 135);
PAINT MONO (-13390 135);
DISPLAY INVISIBLE (-13390 135);
FORCEPROP 2 LAST CDS_LIB logical_power
J 0
(-13400 75);
DISPLAY INVISIBLE (-13400 75);
FORCEPROP 1 LAST PATH I9
J 0
(-13325 75);
DISPLAY 0.872340 (-13325 75);
PAINT AQUA (-13325 75);
DISPLAY INVISIBLE (-13325 75);
FORCEPROP 1 LAST HDL_POWER GND
J 1
(-13375 0);
DISPLAY 0.872340 (-13375 0);
PAINT GREEN (-13375 0);
DISPLAY INVISIBLE (-13375 0);
FORCEADD QUANTA_TITLE_BLOCK_C..1
(-5900 -2075);
FORCEPROP 0 LAST CDS_CON_LAST_MODIFIED Fri Aug 25 14:04:26 2023
J 0
(-7785 -2060);
DISPLAY INVISIBLE (-7785 -2060);
FORCEPROP 1 LAST CUSTOM_TXT_CDS <CON_LAST_MODIFIED>
J 0
(-7785 -2060);
DISPLAY 0.978723 (-7785 -2060);
FORCEPROP 2 LAST CUSTOM_TXT_CDS <XR_PAGE_TITLE>
J 0
(-13790 3175);
DISPLAY 0.638298 (-13790 3175);
PAINT PINK (-13790 3175);
DISPLAY INVISIBLE (-13790 3175);
FORCEPROP 1 LAST CUSTOM_TXT_CDS <NAME_2>
J 0
(-9075 -2025);
FORCEPROP 1 LAST CUSTOM_TXT_CDS <NAME_1>
J 0
(-9075 -1900);
FORCEPROP 1 LAST CUSTOM_TXT_CDS <Q_NUMBER>
J 0
(-7303 -1972);
DISPLAY 1.212766 (-7303 -1972);
FORCEPROP 1 LAST CUSTOM_TXT_CDS <Q_PROJ>
J 0
(-8282 -1973);
DISPLAY 1.212766 (-8282 -1973);
FORCEPROP 1 LAST CUSTOM_TXT_CDS <Q_REV>
J 0
(-6084 -1972);
DISPLAY 1.212766 (-6084 -1972);
FORCEPROP 1 LAST CUSTOM_TXT_CDS <CON_PAGE_NUM> OF <CON_TOTAL_PAGES>
J 0
(-6346 -2057);
DISPLAY 0.978723 (-6346 -2057);
FORCEPROP 1 LAST Q_TITLE POWER GOOD LED'S 4/5
J 0
(-15266 -2049);
DISPLAY 2.446809 (-15266 -2049);
PAINT GREEN (-15266 -2049);
FORCEPROP 1 LAST Q_DEPT 
J 1
(-9663 -2026);
DISPLAY 1.957447 (-9663 -2026);
PAINT GREEN (-9663 -2026);
FORCEPROP 2 LAST CDS_XR_PAGE_TITLE CR-255 : @S9S_MB_2U_LIB.S9S_MB_2U(SCH_1):PAGE255
J 0
(-13790 3175);
DISPLAY 0.638298 (-13790 3175);
PAINT PINK (-13790 3175);
DISPLAY INVISIBLE (-13790 3175);
FORCEPROP 2 LAST PAGE_BORDER TRUE
J 0
(-13790 3175);
DISPLAY 0.638298 (-13790 3175);
PAINT PINK (-13790 3175);
DISPLAY INVISIBLE (-13790 3175);
FORCEPROP 1 LAST CDS_LMAN_SYM_OUTLINE -9475,6775,100,-125
J 0
(-5900 -2075);
DISPLAY 0.468085 (-5900 -2075);
PAINT GREEN (-5900 -2075);
DISPLAY INVISIBLE (-5900 -2075);
FORCEPROP 2 LAST CDS_LIB pure_quanta
J 0
(-5900 -2075);
DISPLAY INVISIBLE (-5900 -2075);
FORCEPROP 1 LAST COMMENT_BODY TRUE
J 0
(-5888 -2088);
DISPLAY 0.978723 (-5888 -2088);
PAINT GREEN (-5888 -2088);
DISPLAY INVISIBLE (-5888 -2088);
WIRE 16 -1 (-6150 675)(-6150 425);
WIRE 16 -1 (-10425 3350)(-10425 3600);
WIRE 16 -1 (-10425 3350)(-11025 3350);
WIRE 16 -1 (-10475 2075)(-10475 2225);
WIRE 16 -1 (-10475 2075)(-11025 2075);
WIRE 16 -1 (-6325 3675)(-6325 3400);
WIRE 16 -1 (-6325 2425)(-6325 2150);
WIRE 16 -1 (-10450 700)(-10450 825);
WIRE 16 -1 (-10450 700)(-10975 700);
WIRE 16 -1 (-9025 675)(-9025 525);
WIRE 16 -1 (-10325 -750)(-10325 -625);
WIRE 16 -1 (-10325 -750)(-10850 -750);
WIRE 16 -1 (-9025 -425)(-9025 -625);
WIRE 16 -1 (-13400 125)(-13400 225);
WIRE 16 -1 (-13450 2775)(-13450 2875);
WIRE 16 -1 (-13450 1500)(-13450 1600);
WIRE 16 -1 (-13375 -1325)(-13375 -1225);
WIRE 16 -1 (-9400 3400)(-9400 3175);
WIRE 16 -1 (-9275 3400)(-9400 3400);
WIRE 16 -1 (-9400 2150)(-9400 1925);
WIRE 16 -1 (-9275 2150)(-9400 2150);
WIRE 16 -1 (-7975 -50)(-7975 -250);
WIRE 16 2175 (-10200 -875)(-5975 -875);
WIRE 16 2175 (-5975 4100)(-5975 -875);
WIRE 16 2175 (-10200 4100)(-10200 -875);
WIRE 16 2175 (-10200 4100)(-5975 4100);
WIRE 74 -1 (-6900 2900)(-9050 2900);
WIRE 74 -1 (-6900 2700)(-6900 2900);
WIRE 74 -1 (-9050 2900)(-9050 2700);
WIRE 74 -1 (-9050 2700)(-6900 2700);
WIRE 74 -1 (-6875 1275)(-9025 1275);
WIRE 74 -1 (-6875 1075)(-6875 1275);
WIRE 74 -1 (-9025 1275)(-9025 1075);
WIRE 74 -1 (-9025 1075)(-6875 1075);
WIRE 16 -1 (-6725 2150)(-6325 2150);
WIRE 16 -1 (-6725 3400)(-6325 3400);
WIRE 16 -1 (-6150 425)(-6425 425);
WIRE 16 -1 (-7975 425)(-7975 350);
WIRE 16 -1 (-7975 425)(-7650 425);
FORCEPROP 2 LAST SIG_NAME LED_P12V_SCM_FAULT_D2
J 0
(-8385 435);
DISPLAY 0.723404 (-8385 435);
WIRE 16 -1 (-8975 2150)(-8500 2150);
FORCEPROP 0 LAST CDS_PHYS_NET_NAME P12V_AUX_CPU0_DIMM_ISEN_P
J 0
(-8885 2181);
PAINT MONO (-8885 2181);
DISPLAY INVISIBLE (-8885 2181);
FORCEPROP 2 LAST SIG_NAME LED_P12V_PSU_R1
J 0
(-8935 2160);
DISPLAY 0.446809 (-8935 2160);
PAINT WHITE (-8935 2160);
WIRE 16 -1 (-9850 -275)(-9275 -275);
FORCEPROP 0 LAST VOLTAGE 0
J 0
(-9710 -238);
DISPLAY INVISIBLE (-9710 -238);
FORCEPROP 2 LAST SIG_NAME P12V_SCM_FAULT_R_N
J 0
(-9785 -265);
DISPLAY 0.574468 (-9785 -265);
WIRE 16 -1 (-9025 100)(-9025 -25);
WIRE 16 -1 (-9025 325)(-9025 100);
WIRE 16 -1 (-8225 100)(-9025 100);
FORCEPROP 2 LAST SIG_NAME LED_P12V_SCM_FAULT_D1
J 0
(-9010 110);
DISPLAY 0.723404 (-9010 110);
WIRE 16 -1 (-7625 3400)(-6925 3400);
FORCEPROP 0 LAST CDS_PHYS_NET_NAME P12V_AUX_CPU0_DIMM_ISEN_P
J 0
(-7535 3431);
PAINT MONO (-7535 3431);
DISPLAY INVISIBLE (-7535 3431);
FORCEPROP 2 LAST SIG_NAME LED_P12V_AUX_R3
J 0
(-7410 3410);
DISPLAY 0.446809 (-7410 3410);
PAINT WHITE (-7410 3410);
WIRE 16 -1 (-7600 2150)(-6925 2150);
FORCEPROP 0 LAST CDS_PHYS_NET_NAME P12V_AUX_CPU0_DIMM_ISEN_P
J 0
(-7510 2181);
PAINT MONO (-7510 2181);
DISPLAY INVISIBLE (-7510 2181);
FORCEPROP 2 LAST SIG_NAME LED_P12V_PSU_R3
J 0
(-7385 2160);
DISPLAY 0.446809 (-7385 2160);
PAINT WHITE (-7385 2160);
WIRE 74 -1 (-6925 4050)(-9075 4050);
WIRE 74 -1 (-6925 3850)(-6925 4050);
WIRE 74 -1 (-9075 4050)(-9075 3850);
WIRE 74 -1 (-9075 3850)(-6925 3850);
WIRE 16 -1 (-8300 3400)(-7825 3400);
FORCEPROP 0 LAST CDS_PHYS_NET_NAME P12V_AUX_CPU0_DIMM_ISEN_P
J 0
(-8210 3431);
PAINT MONO (-8210 3431);
DISPLAY INVISIBLE (-8210 3431);
FORCEPROP 2 LAST SIG_NAME LED_P12V_AUX_R2
J 0
(-8285 3410);
DISPLAY 0.446809 (-8285 3410);
PAINT WHITE (-8285 3410);
WIRE 16 -1 (-7350 425)(-6625 425);
FORCEPROP 2 LAST SIG_NAME LED_P12V_SCM_FAULT
J 0
(-7260 435);
DISPLAY 0.723404 (-7260 435);
WIRE 16 -1 (-12275 3350)(-11225 3350);
FORCEPROP 2 LAST SIG_NAME LED_PWRGD_PCH_PWROK_R
J 0
(-12110 3360);
DISPLAY 0.723404 (-12110 3360);
WIRE 16 -1 (-12200 -750)(-11050 -750);
FORCEPROP 2 LAST SIG_NAME LED_RST_PLTRST_N
J 0
(-12035 -740);
DISPLAY 0.723404 (-12035 -740);
WIRE 16 -1 (-13650 375)(-14500 375);
FORCEPROP 2 LAST SIG_NAME PWRGD_CPUPWRGD_LVC2_R1
J 0
(-14485 385);
DISPLAY 0.723404 (-14485 385);
PAINT WHITE (-14485 385);
WIRE 74 -1 (-12325 2500)(-14475 2500);
WIRE 74 -1 (-12325 2300)(-12325 2500);
WIRE 74 -1 (-14475 2500)(-14475 2300);
WIRE 74 -1 (-14475 2300)(-12325 2300);
WIRE 74 -1 (-12325 1225)(-14475 1225);
WIRE 74 -1 (-12325 1025)(-12325 1225);
WIRE 74 -1 (-14475 1225)(-14475 1025);
WIRE 74 -1 (-14475 1025)(-12325 1025);
WIRE 16 -1 (-12225 700)(-11175 700);
FORCEPROP 2 LAST SIG_NAME LED_PWRGD_CPUPWRGD_GTL
J 0
(-12060 710);
DISPLAY 0.723404 (-12060 710);
WIRE 16 -1 (-13375 -750)(-12500 -750);
WIRE 16 -1 (-13375 -825)(-13375 -750);
FORCEPROP 2 LAST SIG_NAME LED_RST_PLTRST_N_D
J 0
(-13435 -725);
DISPLAY 0.723404 (-13435 -725);
WIRE 74 -1 (-12300 -200)(-14450 -200);
WIRE 74 -1 (-12300 -400)(-12300 -200);
WIRE 74 -1 (-14450 -200)(-14450 -400);
WIRE 74 -1 (-14450 -400)(-12300 -400);
WIRE 16 -1 (-8300 2150)(-7800 2150);
FORCEPROP 0 LAST CDS_PHYS_NET_NAME P12V_AUX_CPU0_DIMM_ISEN_P
J 0
(-8210 2181);
PAINT MONO (-8210 2181);
DISPLAY INVISIBLE (-8210 2181);
FORCEPROP 2 LAST SIG_NAME LED_P12V_PSU_R2
J 0
(-8260 2160);
DISPLAY 0.446809 (-8260 2160);
PAINT WHITE (-8260 2160);
WIRE 16 -1 (-8975 3400)(-8500 3400);
FORCEPROP 0 LAST CDS_PHYS_NET_NAME P12V_AUX_CPU0_DIMM_ISEN_P
J 0
(-8885 3431);
PAINT MONO (-8885 3431);
DISPLAY INVISIBLE (-8885 3431);
FORCEPROP 2 LAST SIG_NAME LED_P12V_AUX_R1
J 0
(-8935 3410);
DISPLAY 0.446809 (-8935 3410);
PAINT WHITE (-8935 3410);
WIRE 16 -1 (-12275 2075)(-11225 2075);
FORCEPROP 2 LAST SIG_NAME LED_PWRGD_SYS_PWROK_R
J 0
(-12110 2085);
DISPLAY 0.723404 (-12110 2085);
WIRE 16 -1 (-13450 3350)(-12575 3350);
FORCEPROP 2 LAST SIG_NAME LED_PWRGD_PCH_PWROK_R_D
J 0
(-13435 3350);
DISPLAY 0.723404 (-13435 3350);
WIRE 16 -1 (-13450 3275)(-13450 3350);
WIRE 74 -1 (-12375 3875)(-14525 3875);
WIRE 74 -1 (-12375 3675)(-12375 3875);
WIRE 74 -1 (-14525 3875)(-14525 3675);
WIRE 74 -1 (-14525 3675)(-12375 3675);
WIRE 16 -1 (-13625 -1075)(-14475 -1075);
FORCEPROP 2 LAST SIG_NAME RST_PLTRST_N
J 0
(-14335 -1065);
DISPLAY 0.723404 (-14335 -1065);
PAINT WHITE (-14335 -1065);
WIRE 16 -1 (-13700 1750)(-14550 1750);
FORCEPROP 2 LAST SIG_NAME PWRGD_SYS_PWROK_R
J 0
(-14360 1760);
DISPLAY 0.723404 (-14360 1760);
WIRE 16 -1 (-13700 3025)(-14550 3025);
FORCEPROP 2 LAST SIG_NAME PWRGD_PCH_PWROK_R
J 0
(-14410 3035);
DISPLAY 0.723404 (-14410 3035);
WIRE 16 -1 (-13450 2000)(-13450 2075);
WIRE 16 -1 (-13450 2075)(-12575 2075);
FORCEPROP 2 LAST SIG_NAME LED_PWRGD_SYS_PWROK_R_D
J 0
(-13435 2075);
DISPLAY 0.723404 (-13435 2075);
WIRE 16 -1 (-13400 700)(-12525 700);
WIRE 16 -1 (-13400 625)(-13400 700);
FORCEPROP 2 LAST SIG_NAME LED_PWRGD_CPUPWRGD_GTL_D
J 0
(-13424 700);
DISPLAY 0.723404 (-13424 700);
DOT 1 (-9025 100);
FORCENOTE
PWRGD_PCH_PWROK          1 = ON
(-14400 3750) 0;
DISPLAY LEFT (-14400 3750);
DISPLAY 1.276596 (-14400 3750);
PAINT WHITE (-14400 3750);
FORCENOTE
RST_PLTRST_N          1 = ON
(-14325 -325) 0;
DISPLAY LEFT (-14325 -325);
DISPLAY 1.276596 (-14325 -325);
PAINT WHITE (-14325 -325);
FORCENOTE
PWRGD_CPUPWRGD_GTL          1 = ON
(-14350 1100) 0;
DISPLAY LEFT (-14350 1100);
DISPLAY 1.276596 (-14350 1100);
PAINT WHITE (-14350 1100);
FORCENOTE
PWRGD_SYS_PWROK          1 = ON
(-14350 2375) 0;
DISPLAY LEFT (-14350 2375);
DISPLAY 1.276596 (-14350 2375);
PAINT WHITE (-14350 2375);
FORCENOTE
20210705 MODIFY FOR GT
(-15225 4250) 0;
DISPLAY LEFT (-15225 4250);
DISPLAY 2.510638 (-15225 4250);
PAINT PINK (-15225 4250);
FORCENOTE
P12V_AUX          1 = ON
(-8950 3925) 0;
DISPLAY LEFT (-8950 3925);
DISPLAY 1.276596 (-8950 3925);
PAINT WHITE (-8950 3925);
FORCENOTE
20220725 ADD LED FOR DEBUG PLAN
(-8725 -1000) 0;
DISPLAY LEFT (-8725 -1000);
DISPLAY 1.063830 (-8725 -1000);
PAINT WHITE (-8725 -1000);
FORCENOTE
P12V_SCM FAULT         0 = ON
(-8900 1150) 0;
DISPLAY LEFT (-8900 1150);
DISPLAY 1.276596 (-8900 1150);
PAINT WHITE (-8900 1150);
FORCENOTE
P12V_PSU          1 = ON
(-8925 2775) 0;
DISPLAY LEFT (-8925 2775);
DISPLAY 1.276596 (-8925 2775);
PAINT WHITE (-8925 2775);
QUIT
